FILE_TYPE = CONNECTIVITY;
{Allegro Design Entry HDL 17.4-2019 S026 (4007227) 1/17/2022}
"PAGE_NUMBER" = 36;
0"NC";
END.
